(kicad_pcb
	(version 20260206)
	(generator "pcbnew")
	(generator_version "10.0")
	(general
		(thickness 1.6)
		(legacy_teardrops no)
	)
	(paper "A4")
	(title_block
		(title "panther-plus-userver — 13130-1b_20150205.brd")
		(comment 1 "Honey Badger (Wiwynn) / footprints 581-586 of 1509")
	)
	(layers
		(0 "F.Cu" signal "TOP")
		(4 "In1.Cu" signal "L2")
		(6 "In2.Cu" signal "L3")
		(8 "In3.Cu" signal "L4")
		(10 "In4.Cu" signal "L5")
		(12 "In5.Cu" signal "L6")
		(14 "In6.Cu" signal "L7")
		(16 "In7.Cu" signal "L8")
		(18 "In8.Cu" signal "L9")
		(20 "In9.Cu" signal "L10")
		(22 "In10.Cu" signal "L11")
		(2 "B.Cu" signal "BOTTOM")
		(9 "F.Adhes" user "F.Adhesive")
		(11 "B.Adhes" user "B.Adhesive")
		(13 "F.Paste" user "Package Geometry/Pastemask Top")
		(15 "B.Paste" user "Package Geometry/Pastemask Bottom")
		(5 "F.SilkS" user "Ref Des/Silkscreen Top")
		(7 "B.SilkS" user "Ref Des/Silkscreen Bottom")
		(1 "F.Mask" user "Board Geometry/Soldermask Top")
		(3 "B.Mask" user "Board Geometry/Soldermask Bottom")
		(17 "Dwgs.User" user "User.Drawings")
		(19 "Cmts.User" user "User.Comments")
		(21 "Eco1.User" user "User.Eco1")
		(23 "Eco2.User" user "User.Eco2")
		(25 "Edge.Cuts" user "Board Geometry/Outline")
		(27 "Margin" user)
		(31 "F.CrtYd" user "Package Geometry/Place Bound Top")
		(29 "B.CrtYd" user "Package Geometry/Place Bound Bottom")
		(35 "F.Fab" user "Ref Des/Assembly Top")
		(33 "B.Fab" user "Ref Des/Assembly Bottom")
	)
	(footprint ""
		(layer "F.Cu")
		(at 77.978 -12.065 -90)
		(property "Reference" "R398"
			(at 0 0 270)
			(layer "F.SilkS")
			(hide yes)
			(effects
				(font
					(size 1.27 1.27)
				)
			)
		)
		(property "Value" "0R2J-2-GP"
			(at 1.7907 -1.1176 270)
			(unlocked yes)
			(layer "F.Fab")
			(hide yes)
			(effects
				(font
					(size 1.016 1.016)
					(thickness 0.1524)
				)
			)
		)
		(property "Device Type" "R402H16"
			(at 1.7907 -2.6416 270)
			(unlocked yes)
			(layer "F.Fab")
			(hide yes)
			(effects
				(font
					(size 1.016 1.016)
					(thickness 0.1524)
				)
			)
		)
		(duplicate_pad_numbers_are_jumpers no)
		(fp_rect
			(start -0.381 0.8382)
			(end 0.381 -0.8382)
			(stroke
				(width 0)
				(type default)
			)
			(fill no)
			(layer "F.CrtYd")
		)
		(fp_rect
			(start -0.381 0.8382)
			(end 0.381 -0.8382)
			(stroke
				(width 0)
				(type default)
			)
			(fill no)
			(layer "F.Fab")
		)
		(pad "1" smd custom
			(at 0 -0.4318 270)
			(size 0.127 0.127)
			(layers "F.Cu" "F.Mask" "F.Paste")
			(net "PCIE_GF_I2C_R_ALERT#")
			(options
				(clearance outline)
				(anchor circle)
			)
			(primitives
				(gr_poly
					(pts
						(arc
							(start -0.2032 -0.2794)
							(mid -0.239121 -0.264521)
							(end -0.254 -0.2286)
						)
						(arc
							(start -0.254 0.2286)
							(mid -0.239121 0.264521)
							(end -0.2032 0.2794)
						)
						(arc
							(start 0.2032 0.2794)
							(mid 0.239121 0.264521)
							(end 0.254 0.2286)
						)
						(arc
							(start 0.254 -0.2286)
							(mid 0.239121 -0.264521)
							(end 0.2032 -0.2794)
						)
					)
					(width 0)
					(fill yes)
				)
			)
		)
		(pad "2" smd custom
			(at 0 0.4318 270)
			(size 0.127 0.127)
			(layers "F.Cu" "F.Mask" "F.Paste")
			(net "PCIE_GF_I2C_ALERT#")
			(options
				(clearance outline)
				(anchor circle)
			)
			(primitives
				(gr_poly
					(pts
						(arc
							(start -0.2032 -0.2794)
							(mid -0.239121 -0.264521)
							(end -0.254 -0.2286)
						)
						(arc
							(start -0.254 0.2286)
							(mid -0.239121 0.264521)
							(end -0.2032 0.2794)
						)
						(arc
							(start 0.2032 0.2794)
							(mid 0.239121 0.264521)
							(end 0.254 0.2286)
						)
						(arc
							(start 0.254 -0.2286)
							(mid 0.239121 -0.264521)
							(end 0.2032 -0.2794)
						)
					)
					(width 0)
					(fill yes)
				)
			)
		)
	)
	(footprint ""
		(layer "F.Cu")
		(at 47.879 -18.415 -90)
		(property "Reference" "R343"
			(at 0 0 270)
			(layer "F.SilkS")
			(hide yes)
			(effects
				(font
					(size 1.27 1.27)
				)
			)
		)
		(property "Value" "4K7R2F-GP"
			(at 0.064008 -3.993896 270)
			(unlocked yes)
			(layer "F.Fab")
			(hide yes)
			(effects
				(font
					(size 1.016 1.016)
					(thickness 0.1524)
				)
			)
		)
		(property "Device Type" "R402H16"
			(at 0.064008 -5.517896 270)
			(unlocked yes)
			(layer "F.Fab")
			(hide yes)
			(effects
				(font
					(size 1.016 1.016)
					(thickness 0.1524)
				)
			)
		)
		(duplicate_pad_numbers_are_jumpers no)
		(fp_rect
			(start -0.381 0.8382)
			(end 0.381 -0.8382)
			(stroke
				(width 0)
				(type default)
			)
			(fill no)
			(layer "F.CrtYd")
		)
		(fp_rect
			(start -0.381 0.8382)
			(end 0.381 -0.8382)
			(stroke
				(width 0)
				(type default)
			)
			(fill no)
			(layer "F.Fab")
		)
		(pad "1" smd custom
			(at 0 -0.4318 270)
			(size 0.127 0.127)
			(layers "F.Cu" "F.Mask" "F.Paste")
			(net "CLKBUFF_OE3#")
			(options
				(clearance outline)
				(anchor circle)
			)
			(primitives
				(gr_poly
					(pts
						(arc
							(start -0.2032 -0.2794)
							(mid -0.239121 -0.264521)
							(end -0.254 -0.2286)
						)
						(arc
							(start -0.254 0.2286)
							(mid -0.239121 0.264521)
							(end -0.2032 0.2794)
						)
						(arc
							(start 0.2032 0.2794)
							(mid 0.239121 0.264521)
							(end 0.254 0.2286)
						)
						(arc
							(start 0.254 -0.2286)
							(mid 0.239121 -0.264521)
							(end 0.2032 -0.2794)
						)
					)
					(width 0)
					(fill yes)
				)
			)
		)
		(pad "2" smd custom
			(at 0 0.4318 270)
			(size 0.127 0.127)
			(layers "F.Cu" "F.Mask" "F.Paste")
			(net "GND")
			(options
				(clearance outline)
				(anchor circle)
			)
			(primitives
				(gr_poly
					(pts
						(arc
							(start -0.2032 -0.2794)
							(mid -0.239121 -0.264521)
							(end -0.254 -0.2286)
						)
						(arc
							(start -0.254 0.2286)
							(mid -0.239121 0.264521)
							(end -0.2032 0.2794)
						)
						(arc
							(start 0.2032 0.2794)
							(mid 0.239121 0.264521)
							(end 0.254 0.2286)
						)
						(arc
							(start 0.254 -0.2286)
							(mid 0.239121 -0.264521)
							(end 0.2032 -0.2794)
						)
					)
					(width 0)
					(fill yes)
				)
			)
		)
	)
	(footprint ""
		(layer "F.Cu")
		(at 40.767 -42.926)
		(property "Reference" "U6"
			(at 0 0 0)
			(layer "F.SilkS")
			(hide yes)
			(effects
				(font
					(size 1.27 1.27)
				)
			)
		)
		(property "Value" "SN74LVC1G14DCKR-GP"
			(at 0 -8.0772 0)
			(unlocked yes)
			(layer "F.Fab")
			(hide yes)
			(effects
				(font
					(size 1.016 1.016)
					(thickness 0.1524)
				)
			)
		)
		(property "Device Type" "SC70-5H44"
			(at 0 -9.6012 0)
			(unlocked yes)
			(layer "F.Fab")
			(hide yes)
			(effects
				(font
					(size 1.016 1.016)
					(thickness 0.1524)
				)
			)
		)
		(duplicate_pad_numbers_are_jumpers no)
		(fp_line
			(start -1.0033 -0.3302)
			(end 1.0033 -0.3302)
			(stroke
				(width 0.1524)
				(type default)
			)
			(layer "F.SilkS")
		)
		(fp_line
			(start -1.0033 0.3302)
			(end -1.0033 -0.3302)
			(stroke
				(width 0.1524)
				(type default)
			)
			(layer "F.SilkS")
		)
		(fp_line
			(start 1.0033 -0.3302)
			(end 1.0033 0.3302)
			(stroke
				(width 0.1524)
				(type default)
			)
			(layer "F.SilkS")
		)
		(fp_line
			(start 1.0033 0.3302)
			(end -1.0033 0.3302)
			(stroke
				(width 0.1524)
				(type default)
			)
			(layer "F.SilkS")
		)
		(fp_poly
			(pts
				(xy -1.0033 1.4859) (xy -1.0033 0.8001) (xy -1.1811 0.8001) (xy -1.1811 -0.8001) (xy -1.0033 -0.8001)
				(xy -1.0033 -1.4859) (xy 1.0033 -1.4859) (xy 1.0033 -0.8001) (xy 1.1811 -0.8001) (xy 1.1811 0.8001)
				(xy 1.0033 0.8001) (xy 1.0033 1.4859) (xy 0.2921 1.4859) (xy 0.2921 0.8001) (xy -0.2921 0.8001)
				(xy -0.2921 1.4859)
			)
			(stroke
				(width 0)
				(type default)
			)
			(fill no)
			(layer "F.CrtYd")
		)
		(fp_poly
			(pts
				(xy -1.0033 1.4859) (xy -1.0033 0.8001) (xy -1.1811 0.8001) (xy -1.1811 -0.8001) (xy -1.0033 -0.8001)
				(xy -1.0033 -1.4859) (xy 1.0033 -1.4859) (xy 1.0033 -0.8001) (xy 1.1811 -0.8001) (xy 1.1811 0.8001)
				(xy 1.0033 0.8001) (xy 1.0033 1.4859) (xy 0.2921 1.4859) (xy 0.2921 0.8001) (xy -0.2921 0.8001)
				(xy -0.2921 1.4859)
			)
			(stroke
				(width 0)
				(type default)
			)
			(fill no)
			(layer "F.Fab")
		)
		(pad "1" smd rect
			(at 0.65024 -0.93472)
			(size 0.3556 0.762)
			(layers "F.Cu" "F.Mask" "F.Paste")
			(net "Net_446")
		)
		(pad "2" smd rect
			(at 0 -0.93472)
			(size 0.3556 0.762)
			(layers "F.Cu" "F.Mask" "F.Paste")
			(net "P3V3_CPU_PG_S1")
		)
		(pad "3" smd rect
			(at -0.65024 -0.93472)
			(size 0.3556 0.762)
			(layers "F.Cu" "F.Mask" "F.Paste")
			(net "GND")
		)
		(pad "4" smd rect
			(at -0.65024 0.93472)
			(size 0.3556 0.762)
			(layers "F.Cu" "F.Mask" "F.Paste")
			(net "P3V3_CPU_PG_S2")
		)
		(pad "5" smd rect
			(at 0.65024 0.93472)
			(size 0.3556 0.762)
			(layers "F.Cu" "F.Mask" "F.Paste")
			(net "P3V3_STBY")
		)
	)
	(footprint ""
		(layer "F.Cu")
		(at 27.305 -17.9451)
		(property "Reference" "SW3"
			(at 0 0 0)
			(layer "F.SilkS")
			(hide yes)
			(effects
				(font
					(size 1.27 1.27)
				)
			)
		)
		(property "Value" "SW-PUSH-2P-6-GP"
			(at -4.2291 1.2573 0)
			(unlocked yes)
			(layer "F.Fab")
			(hide yes)
			(effects
				(font
					(size 1.016 1.016)
					(thickness 0.1524)
				)
			)
		)
		(property "Device Type" "TL1015AF160QG-2"
			(at -4.2291 -0.2667 0)
			(unlocked yes)
			(layer "F.Fab")
			(hide yes)
			(effects
				(font
					(size 1.016 1.016)
					(thickness 0.1524)
				)
			)
		)
		(duplicate_pad_numbers_are_jumpers no)
		(fp_poly
			(pts
				(xy -2.726944 0.01905) (xy -3.29057 0.582676) (xy -3.29057 -0.544576)
			)
			(stroke
				(width 0)
				(type default)
			)
			(fill yes)
			(layer "F.SilkS")
		)
		(fp_poly
			(pts
				(xy -2.2098 1.905) (xy -2.2098 0.8255) (xy -2.6797 0.8255) (xy -2.6797 -0.8255) (xy -2.2098 -0.8255)
				(xy -2.2098 -1.905) (xy 2.2098 -1.905) (xy 2.2098 -0.8255) (xy 2.6797 -0.8255) (xy 2.6797 0.8255)
				(xy 2.2098 0.8255) (xy 2.2098 1.905)
			)
			(stroke
				(width 0)
				(type default)
			)
			(fill no)
			(layer "F.CrtYd")
		)
		(fp_poly
			(pts
				(xy -2.2098 1.905) (xy -2.2098 0.8255) (xy -2.6797 0.8255) (xy -2.6797 -0.8255) (xy -2.2098 -0.8255)
				(xy -2.2098 -1.905) (xy 2.2098 -1.905) (xy 2.2098 -0.8255) (xy 2.6797 -0.8255) (xy 2.6797 0.8255)
				(xy 2.2098 0.8255) (xy 2.2098 1.905)
			)
			(stroke
				(width 0)
				(type default)
			)
			(fill no)
			(layer "F.Fab")
		)
		(pad "1" smd rect
			(at -2.074926 0)
			(size 0.9398 1.397)
			(layers "F.Cu" "F.Mask" "F.Paste")
			(net "GND")
		)
		(pad "2" smd rect
			(at 2.074926 0)
			(size 0.9398 1.397)
			(layers "F.Cu" "F.Mask" "F.Paste")
			(net "XDP_BUF_RTEST#")
		)
		(zone
			(layer "F.Cu")
			(hatch none 0.5)
			(connect_pads
				(clearance 0)
			)
			(min_thickness 0.25)
			(keepout
				(tracks not_allowed)
				(vias allowed)
				(pads allowed)
				(copperpour not_allowed)
				(footprints allowed)
			)
			(placement
				(enabled no)
				(sheetname "")
			)
			(fill
				(thermal_gap 0.5)
				(thermal_bridge_width 0.5)
				(island_removal_mode 0)
			)
			(polygon
				(pts
					(xy 25.15489 -19.84502) (xy 25.15489 -19.095212) (xy 26.305002 -19.095212) (xy 26.305002 -19.84502)
				)
			)
		)
		(zone
			(layer "F.Cu")
			(hatch none 0.5)
			(connect_pads
				(clearance 0)
			)
			(min_thickness 0.25)
			(keepout
				(tracks allowed)
				(vias not_allowed)
				(pads allowed)
				(copperpour not_allowed)
				(footprints allowed)
			)
			(placement
				(enabled no)
				(sheetname "")
			)
			(fill
				(thermal_gap 0.5)
				(thermal_bridge_width 0.5)
				(island_removal_mode 0)
			)
			(polygon
				(pts
					(xy 25.15489 -19.095212) (xy 26.305002 -19.095212) (xy 26.305002 -19.84502) (xy 25.15489 -19.84502)
				)
			)
		)
		(zone
			(layer "F.Cu")
			(hatch none 0.5)
			(connect_pads
				(clearance 0)
			)
			(min_thickness 0.25)
			(keepout
				(tracks not_allowed)
				(vias allowed)
				(pads allowed)
				(copperpour not_allowed)
				(footprints allowed)
			)
			(placement
				(enabled no)
				(sheetname "")
			)
			(fill
				(thermal_gap 0.5)
				(thermal_bridge_width 0.5)
				(island_removal_mode 0)
			)
			(polygon
				(pts
					(xy 25.15489 -16.794988) (xy 25.15489 -16.04518) (xy 26.305002 -16.04518) (xy 26.305002 -16.794988)
				)
			)
		)
		(zone
			(layer "F.Cu")
			(hatch none 0.5)
			(connect_pads
				(clearance 0)
			)
			(min_thickness 0.25)
			(keepout
				(tracks allowed)
				(vias not_allowed)
				(pads allowed)
				(copperpour not_allowed)
				(footprints allowed)
			)
			(placement
				(enabled no)
				(sheetname "")
			)
			(fill
				(thermal_gap 0.5)
				(thermal_bridge_width 0.5)
				(island_removal_mode 0)
			)
			(polygon
				(pts
					(xy 25.15489 -16.04518) (xy 26.305002 -16.04518) (xy 26.305002 -16.794988) (xy 25.15489 -16.794988)
				)
			)
		)
		(zone
			(layer "F.Cu")
			(hatch none 0.5)
			(connect_pads
				(clearance 0)
			)
			(min_thickness 0.25)
			(keepout
				(tracks not_allowed)
				(vias allowed)
				(pads allowed)
				(copperpour not_allowed)
				(footprints allowed)
			)
			(placement
				(enabled no)
				(sheetname "")
			)
			(fill
				(thermal_gap 0.5)
				(thermal_bridge_width 0.5)
				(island_removal_mode 0)
			)
			(polygon
				(pts
					(xy 28.304998 -19.84502) (xy 28.304998 -19.095212) (xy 29.45511 -19.095212) (xy 29.45511 -19.84502)
				)
			)
		)
		(zone
			(layer "F.Cu")
			(hatch none 0.5)
			(connect_pads
				(clearance 0)
			)
			(min_thickness 0.25)
			(keepout
				(tracks allowed)
				(vias not_allowed)
				(pads allowed)
				(copperpour not_allowed)
				(footprints allowed)
			)
			(placement
				(enabled no)
				(sheetname "")
			)
			(fill
				(thermal_gap 0.5)
				(thermal_bridge_width 0.5)
				(island_removal_mode 0)
			)
			(polygon
				(pts
					(xy 28.304998 -19.095212) (xy 29.45511 -19.095212) (xy 29.45511 -19.84502) (xy 28.304998 -19.84502)
				)
			)
		)
		(zone
			(layer "F.Cu")
			(hatch none 0.5)
			(connect_pads
				(clearance 0)
			)
			(min_thickness 0.25)
			(keepout
				(tracks not_allowed)
				(vias allowed)
				(pads allowed)
				(copperpour not_allowed)
				(footprints allowed)
			)
			(placement
				(enabled no)
				(sheetname "")
			)
			(fill
				(thermal_gap 0.5)
				(thermal_bridge_width 0.5)
				(island_removal_mode 0)
			)
			(polygon
				(pts
					(xy 28.304998 -16.794988) (xy 28.304998 -16.04518) (xy 29.45511 -16.04518) (xy 29.45511 -16.794988)
				)
			)
		)
		(zone
			(layer "F.Cu")
			(hatch none 0.5)
			(connect_pads
				(clearance 0)
			)
			(min_thickness 0.25)
			(keepout
				(tracks allowed)
				(vias not_allowed)
				(pads allowed)
				(copperpour not_allowed)
				(footprints allowed)
			)
			(placement
				(enabled no)
				(sheetname "")
			)
			(fill
				(thermal_gap 0.5)
				(thermal_bridge_width 0.5)
				(island_removal_mode 0)
			)
			(polygon
				(pts
					(xy 28.304998 -16.04518) (xy 29.45511 -16.04518) (xy 29.45511 -16.794988) (xy 28.304998 -16.794988)
				)
			)
		)
	)
	(footprint ""
		(layer "F.Cu")
		(at 141.859 -47.4472 -90)
		(property "Reference" "R433"
			(at 0 0 270)
			(layer "F.SilkS")
			(hide yes)
			(effects
				(font
					(size 1.27 1.27)
				)
			)
		)
		(property "Value" "1KR2F-3-GP"
			(at 1.7907 -1.1176 270)
			(unlocked yes)
			(layer "F.Fab")
			(hide yes)
			(effects
				(font
					(size 1.016 1.016)
					(thickness 0.1524)
				)
			)
		)
		(property "Device Type" "R402H16"
			(at 1.7907 -2.6416 270)
			(unlocked yes)
			(layer "F.Fab")
			(hide yes)
			(effects
				(font
					(size 1.016 1.016)
					(thickness 0.1524)
				)
			)
		)
		(duplicate_pad_numbers_are_jumpers no)
		(fp_rect
			(start -0.381 0.8382)
			(end 0.381 -0.8382)
			(stroke
				(width 0)
				(type default)
			)
			(fill no)
			(layer "F.CrtYd")
		)
		(fp_rect
			(start -0.381 0.8382)
			(end 0.381 -0.8382)
			(stroke
				(width 0)
				(type default)
			)
			(fill no)
			(layer "F.Fab")
		)
		(pad "1" smd custom
			(at 0 -0.4318 270)
			(size 0.127 0.127)
			(layers "F.Cu" "F.Mask" "F.Paste")
			(net "JTAG_PLD_TMS")
			(options
				(clearance outline)
				(anchor circle)
			)
			(primitives
				(gr_poly
					(pts
						(arc
							(start -0.2032 -0.2794)
							(mid -0.239121 -0.264521)
							(end -0.254 -0.2286)
						)
						(arc
							(start -0.254 0.2286)
							(mid -0.239121 0.264521)
							(end -0.2032 0.2794)
						)
						(arc
							(start 0.2032 0.2794)
							(mid 0.239121 0.264521)
							(end 0.254 0.2286)
						)
						(arc
							(start 0.254 -0.2286)
							(mid 0.239121 -0.264521)
							(end 0.2032 -0.2794)
						)
					)
					(width 0)
					(fill yes)
				)
			)
		)
		(pad "2" smd custom
			(at 0 0.4318 270)
			(size 0.127 0.127)
			(layers "F.Cu" "F.Mask" "F.Paste")
			(net "GND")
			(options
				(clearance outline)
				(anchor circle)
			)
			(primitives
				(gr_poly
					(pts
						(arc
							(start -0.2032 -0.2794)
							(mid -0.239121 -0.264521)
							(end -0.254 -0.2286)
						)
						(arc
							(start -0.254 0.2286)
							(mid -0.239121 0.264521)
							(end -0.2032 0.2794)
						)
						(arc
							(start 0.2032 0.2794)
							(mid 0.239121 0.264521)
							(end 0.254 0.2286)
						)
						(arc
							(start 0.254 -0.2286)
							(mid 0.239121 -0.264521)
							(end 0.2032 -0.2794)
						)
					)
					(width 0)
					(fill yes)
				)
			)
		)
	)
	(footprint ""
		(layer "F.Cu")
		(at 141.2748 -56.8198 -90)
		(property "Reference" "PR67"
			(at 0 0 270)
			(layer "F.SilkS")
			(hide yes)
			(effects
				(font
					(size 1.27 1.27)
				)
			)
		)
		(property "Value" "0R2J-2-GP"
			(at 0.064008 -3.993896 270)
			(unlocked yes)
			(layer "F.Fab")
			(hide yes)
			(effects
				(font
					(size 1.016 1.016)
					(thickness 0.1524)
				)
			)
		)
		(property "Device Type" "R402H16"
			(at 0.064008 -5.517896 270)
			(unlocked yes)
			(layer "F.Fab")
			(hide yes)
			(effects
				(font
					(size 1.016 1.016)
					(thickness 0.1524)
				)
			)
		)
		(duplicate_pad_numbers_are_jumpers no)
		(fp_rect
			(start -0.381 0.8382)
			(end 0.381 -0.8382)
			(stroke
				(width 0)
				(type default)
			)
			(fill no)
			(layer "F.CrtYd")
		)
		(fp_rect
			(start -0.381 0.8382)
			(end 0.381 -0.8382)
			(stroke
				(width 0)
				(type default)
			)
			(fill no)
			(layer "F.Fab")
		)
		(pad "1" smd custom
			(at 0 -0.4318 270)
			(size 0.127 0.127)
			(layers "F.Cu" "F.Mask" "F.Paste")
			(net "PWRGD_PVTT_PG")
			(options
				(clearance outline)
				(anchor circle)
			)
			(primitives
				(gr_poly
					(pts
						(arc
							(start -0.2032 -0.2794)
							(mid -0.239121 -0.264521)
							(end -0.254 -0.2286)
						)
						(arc
							(start -0.254 0.2286)
							(mid -0.239121 0.264521)
							(end -0.2032 0.2794)
						)
						(arc
							(start 0.2032 0.2794)
							(mid 0.239121 0.264521)
							(end 0.254 0.2286)
						)
						(arc
							(start 0.254 -0.2286)
							(mid 0.239121 -0.264521)
							(end 0.2032 -0.2794)
						)
					)
					(width 0)
					(fill yes)
				)
			)
		)
		(pad "2" smd custom
			(at 0 0.4318 270)
			(size 0.127 0.127)
			(layers "F.Cu" "F.Mask" "F.Paste")
			(net "PV_VTT_DDR_R_PG")
			(options
				(clearance outline)
				(anchor circle)
			)
			(primitives
				(gr_poly
					(pts
						(arc
							(start -0.2032 -0.2794)
							(mid -0.239121 -0.264521)
							(end -0.254 -0.2286)
						)
						(arc
							(start -0.254 0.2286)
							(mid -0.239121 0.264521)
							(end -0.2032 0.2794)
						)
						(arc
							(start 0.2032 0.2794)
							(mid 0.239121 0.264521)
							(end 0.254 0.2286)
						)
						(arc
							(start 0.254 -0.2286)
							(mid 0.239121 -0.264521)
							(end 0.2032 -0.2794)
						)
					)
					(width 0)
					(fill yes)
				)
			)
		)
	)
)
